# T6G (Grand Teton) — schematic netlist excerpt (pin names and nets, part order shuffled) for the footprints in the layout excerpt that follows; sources: Cadence DE-HDL packaged netlist, KiCad conversion of 04192023_DAF0TMB3IC0_F0TG_MB_C_brd_V02_OCP.brd

C1978  Q_CAP  0.1UF 25V 10% X7R  pkg 0402  page 126 : A = GPU_PRSNT_N_ISO ; B = GND
R458  Q_RES  30K 1% EMPTY  pkg 0402LF  page 29 : A = PVDD18_S5_P0 ; B = ESPI_CPU0_ALERT_P0_N

(kicad_pcb
	(version 20260206)
	(generator "pcbnew")
	(generator_version "10.0")
	(general
		(thickness 1.6)
		(legacy_teardrops no)
	)
	(paper "A4")
	(title_block
		(title "04192023_DAF0TMB3IC0_F0TG_MB_C_brd_V02_OCP.brd")
		(comment 1 "Grand Teton / footprints 6318-6319 of 8354")
	)
	(layers
		(0 "F.Cu" signal "TOP")
		(4 "In1.Cu" signal "GND")
		(6 "In2.Cu" signal "IN1")
		(8 "In3.Cu" signal "GND1")
		(10 "In4.Cu" signal "IN2")
		(12 "In5.Cu" signal "GND2")
		(14 "In6.Cu" signal "IN3")
		(16 "In7.Cu" signal "GND3")
		(18 "In8.Cu" signal "VCC")
		(20 "In9.Cu" signal "VCC1")
		(22 "In10.Cu" signal "GND4")
		(24 "In11.Cu" signal "IN4")
		(26 "In12.Cu" signal "GND5")
		(28 "In13.Cu" signal "IN5")
		(30 "In14.Cu" signal "GND6")
		(32 "In15.Cu" signal "IN6")
		(34 "In16.Cu" signal "GND7")
		(2 "B.Cu" signal "BOTTOM")
		(9 "F.Adhes" user "F.Adhesive")
		(11 "B.Adhes" user "B.Adhesive")
		(13 "F.Paste" user "Package Geometry/Pastemask Top")
		(15 "B.Paste" user "Package Geometry/Pastemask Bottom")
		(5 "F.SilkS" user "Ref Des/Silkscreen Top")
		(7 "B.SilkS" user "Ref Des/Silkscreen Bottom")
		(1 "F.Mask" user "Board Geometry/Soldermask Top")
		(3 "B.Mask" user "Board Geometry/Soldermask Bottom")
		(17 "Dwgs.User" user "User.Drawings")
		(19 "Cmts.User" user "User.Comments")
		(21 "Eco1.User" user "User.Eco1")
		(23 "Eco2.User" user "User.Eco2")
		(25 "Edge.Cuts" user "Board Geometry/Outline")
		(27 "Margin" user)
		(31 "F.CrtYd" user "Package Geometry/Place Bound Top")
		(29 "B.CrtYd" user "Package Geometry/Place Bound Bottom")
		(35 "F.Fab" user "Ref Des/Assembly Top")
		(33 "B.Fab" user "Ref Des/Assembly Bottom")
	)
	(footprint ""
		(layer "B.Cu")
		(at 51.766978 -428.06493 90)
		(property "Reference" "C1978"
			(at 0 0 90)
			(layer "B.SilkS")
			(hide yes)
			(effects
				(font
					(size 1.27 1.27)
				)
				(justify mirror)
			)
		)
		(property "Value" ""
			(at 0 0 90)
			(layer "B.Fab")
			(effects
				(font
					(size 1.27 1.27)
				)
				(justify mirror)
			)
		)
		(duplicate_pad_numbers_are_jumpers no)
		(fp_line
			(start 0.7874 -0.4064)
			(end -0.7874 -0.4064)
			(stroke
				(width 0.1524)
				(type default)
			)
			(layer "B.SilkS")
		)
		(fp_line
			(start -0.7874 -0.4064)
			(end -0.7874 0.4064)
			(stroke
				(width 0.1524)
				(type default)
			)
			(layer "B.SilkS")
		)
		(fp_line
			(start 0.7874 0.4064)
			(end 0.7874 -0.4064)
			(stroke
				(width 0.1524)
				(type default)
			)
			(layer "B.SilkS")
		)
		(fp_line
			(start -0.7874 0.4064)
			(end 0.7874 0.4064)
			(stroke
				(width 0.1524)
				(type default)
			)
			(layer "B.SilkS")
		)
		(fp_line
			(start 0.67945 -0.305054)
			(end 0.12065 -0.305054)
			(stroke
				(width 0.1)
				(type default)
			)
			(layer "B.Fab")
		)
		(fp_line
			(start 0.12065 -0.305054)
			(end 0.12065 -0.2794)
			(stroke
				(width 0.1)
				(type default)
			)
			(layer "B.Fab")
		)
		(fp_line
			(start -0.12065 -0.3048)
			(end -0.67945 -0.3048)
			(stroke
				(width 0.1)
				(type default)
			)
			(layer "B.Fab")
		)
		(fp_line
			(start -0.67945 -0.3048)
			(end -0.67945 0.3048)
			(stroke
				(width 0.1)
				(type default)
			)
			(layer "B.Fab")
		)
		(fp_line
			(start 0.12065 -0.2794)
			(end -0.12065 -0.2794)
			(stroke
				(width 0.1)
				(type default)
			)
			(layer "B.Fab")
		)
		(fp_line
			(start -0.12065 -0.2794)
			(end -0.12065 -0.3048)
			(stroke
				(width 0.1)
				(type default)
			)
			(layer "B.Fab")
		)
		(fp_line
			(start 0.12065 0.2794)
			(end 0.12065 0.3048)
			(stroke
				(width 0.1)
				(type default)
			)
			(layer "B.Fab")
		)
		(fp_line
			(start -0.120396 0.2794)
			(end 0.12065 0.2794)
			(stroke
				(width 0.1)
				(type default)
			)
			(layer "B.Fab")
		)
		(fp_line
			(start 0.67945 0.3048)
			(end 0.67945 -0.305054)
			(stroke
				(width 0.1)
				(type default)
			)
			(layer "B.Fab")
		)
		(fp_line
			(start 0.12065 0.3048)
			(end 0.67945 0.3048)
			(stroke
				(width 0.1)
				(type default)
			)
			(layer "B.Fab")
		)
		(fp_line
			(start -0.120396 0.3048)
			(end -0.120396 0.2794)
			(stroke
				(width 0.1)
				(type default)
			)
			(layer "B.Fab")
		)
		(fp_line
			(start -0.67945 0.3048)
			(end -0.120396 0.3048)
			(stroke
				(width 0.1)
				(type default)
			)
			(layer "B.Fab")
		)
		(pad "1" smd circle
			(at 0.40005 0 270)
			(size 0 0)
			(layers "B.Cu" "B.Mask" "B.Paste")
			(net "GPU_PRSNT_N_ISO")
		)
		(pad "2" smd circle
			(at -0.40005 0 270)
			(size 0 0)
			(layers "B.Cu" "B.Mask" "B.Paste")
			(net "GND")
		)
	)
	(footprint ""
		(layer "B.Cu")
		(at 406.698958 -323.846952)
		(property "Reference" "R458"
			(at 0 0 0)
			(layer "B.SilkS")
			(hide yes)
			(effects
				(font
					(size 1.27 1.27)
				)
				(justify mirror)
			)
		)
		(property "Value" ""
			(at 0 0 0)
			(layer "B.Fab")
			(effects
				(font
					(size 1.27 1.27)
				)
				(justify mirror)
			)
		)
		(duplicate_pad_numbers_are_jumpers no)
		(fp_line
			(start -0.7874 -0.4064)
			(end -0.7874 0.4064)
			(stroke
				(width 0.1524)
				(type default)
			)
			(layer "B.SilkS")
		)
		(fp_line
			(start -0.7874 0.4064)
			(end 0.7874 0.4064)
			(stroke
				(width 0.1524)
				(type default)
			)
			(layer "B.SilkS")
		)
		(fp_line
			(start 0.7874 -0.4064)
			(end -0.7874 -0.4064)
			(stroke
				(width 0.1524)
				(type default)
			)
			(layer "B.SilkS")
		)
		(fp_line
			(start 0.7874 0.4064)
			(end 0.7874 -0.4064)
			(stroke
				(width 0.1524)
				(type default)
			)
			(layer "B.SilkS")
		)
		(fp_line
			(start -0.67945 -0.3048)
			(end -0.67945 0.3048)
			(stroke
				(width 0.1)
				(type default)
			)
			(layer "B.Fab")
		)
		(fp_line
			(start -0.67945 0.3048)
			(end -0.120396 0.3048)
			(stroke
				(width 0.1)
				(type default)
			)
			(layer "B.Fab")
		)
		(fp_line
			(start -0.12065 -0.3048)
			(end -0.67945 -0.3048)
			(stroke
				(width 0.1)
				(type default)
			)
			(layer "B.Fab")
		)
		(fp_line
			(start -0.12065 -0.2794)
			(end -0.12065 -0.3048)
			(stroke
				(width 0.1)
				(type default)
			)
			(layer "B.Fab")
		)
		(fp_line
			(start -0.120396 0.2794)
			(end 0.12065 0.2794)
			(stroke
				(width 0.1)
				(type default)
			)
			(layer "B.Fab")
		)
		(fp_line
			(start -0.120396 0.3048)
			(end -0.120396 0.2794)
			(stroke
				(width 0.1)
				(type default)
			)
			(layer "B.Fab")
		)
		(fp_line
			(start 0.12065 -0.305054)
			(end 0.12065 -0.2794)
			(stroke
				(width 0.1)
				(type default)
			)
			(layer "B.Fab")
		)
		(fp_line
			(start 0.12065 -0.2794)
			(end -0.12065 -0.2794)
			(stroke
				(width 0.1)
				(type default)
			)
			(layer "B.Fab")
		)
		(fp_line
			(start 0.12065 0.2794)
			(end 0.12065 0.3048)
			(stroke
				(width 0.1)
				(type default)
			)
			(layer "B.Fab")
		)
		(fp_line
			(start 0.12065 0.3048)
			(end 0.67945 0.3048)
			(stroke
				(width 0.1)
				(type default)
			)
			(layer "B.Fab")
		)
		(fp_line
			(start 0.67945 -0.305054)
			(end 0.12065 -0.305054)
			(stroke
				(width 0.1)
				(type default)
			)
			(layer "B.Fab")
		)
		(fp_line
			(start 0.67945 0.3048)
			(end 0.67945 -0.305054)
			(stroke
				(width 0.1)
				(type default)
			)
			(layer "B.Fab")
		)
		(pad "1" smd circle
			(at 0.40005 0 180)
			(size 0 0)
			(layers "B.Cu" "B.Mask" "B.Paste")
			(net "PVDD18_S5_P0")
		)
		(pad "2" smd circle
			(at -0.40005 0 180)
			(size 0 0)
			(layers "B.Cu" "B.Mask" "B.Paste")
			(net "ESPI_CPU0_ALERT_P0_N")
		)
	)
)
